#ISCELL
  mstr_misc dns *
  *
#ISCELL
  pure_quanta quanta_title_block_c *
  *
#ISCELL
  pure_quanta_power universal_gnd *
  page184_i1
#ISCELL
  pure_quanta_power universal_gnd *
  page184_i10
#CELL
  pure_quanta q_cap *
  page184_i11
#CELL
  pure_quanta q_res *
  page184_i12
#ISCELL
  pure_quanta_power universal_gnd *
  page184_i13
#ISCELL
  mstr_symbols universal_power *
  page184_i14
#CELL
  pure_quanta q_res *
  page184_i15
#ISCELL
  pure_quanta_power universal_gnd *
  page184_i16
#CELL
  pure_quanta q_res *
  page184_i17
#CELL
  pure_quanta mpq8633bglec838z *
  page184_i18
#ISCELL
  pure_quanta_power universal_gnd *
  page184_i19
#ISCELL
  standard offpage *
  page184_i2
#ISCELL
  pure_quanta_power universal_gnd *
  page184_i20
#CELL
  pure_quanta q_cap *
  page184_i21
#CELL
  pure_quanta q_cap *
  page184_i22
#CELL
  pure_quanta q_res *
  page184_i23
#CELL
  pure_quanta q_cap *
  page184_i24
#CELL
  pure_quanta q_cap *
  page184_i25
#CELL
  pure_quanta q_cap *
  page184_i26
#CELL
  pure_quanta q_cap *
  page184_i27
#CELL
  pure_quanta q_cap *
  page184_i28
#CELL
  pure_quanta q_res *
  page184_i29
#ISCELL
  pure_quanta_power universal_gnd *
  page184_i3
#ISCELL
  mstr_symbols universal_power *
  page184_i30
#CELL
  pure_quanta q_res *
  page184_i31
#ISCELL
  pure_quanta_power universal_gnd *
  page184_i32
#CELL
  pure_quanta q_cap *
  page184_i33
#CELL
  pure_quanta q_cap *
  page184_i34
#CELL
  pure_quanta q_res *
  page184_i35
#CELL
  pure_quanta q_inductor *
  page184_i36
#CELL
  pure_quanta q_res *
  page184_i37
#CELL
  pure_quanta q_res *
  page184_i38
#CELL
  pure_quanta q_cap *
  page184_i39
#CELL
  pure_quanta q_cap *
  page184_i4
#CELL
  pure_quanta q_cap *
  page184_i40
#CELL
  pure_quanta q_cap *
  page184_i41
#CELL
  pure_quanta q_res *
  page184_i42
#ISCELL
  standard offpage *
  page184_i43
#ISCELL
  standard offpage *
  page184_i44
#ISCELL
  pure_quanta_power universal_gnd *
  page184_i45
#CELL
  pure_quanta q_cap *
  page184_i46
#CELL
  pure_quanta q_capp *
  page184_i47
#CELL
  pure_quanta q_cap *
  page184_i48
#ISCELL
  pure_quanta_power universal_gnd *
  page184_i49
#CELL
  pure_quanta q_cap *
  page184_i5
#ISCELL
  pure_quanta_power p1v0 *
  page184_i50
#CELL
  pure_quanta q_res *
  page184_i51
#CELL
  pure_quanta q_res *
  page184_i52
#ISCELL
  standard offpage *
  page184_i53
#CELL
  pure_quanta q_cap *
  page184_i54
#ISCELL
  pure_quanta_power universal_gnd *
  page184_i55
#CELL
  pure_quanta q_cap *
  page184_i56
#CELL
  pure_quanta q_cap *
  page184_i57
#CELL
  pure_quanta q_res *
  page184_i58
#ISCELL
  mstr_symbols p1v0_aux *
  page184_i6
#CELL
  pure_quanta q_inductor *
  page184_i7
#CELL
  pure_quanta q_cap *
  page184_i8
#ISCELL
  pure_quanta_power universal_gnd *
  page184_i9
